# BASEBOARD_FAB2 (Tioga Pass) — schematic netlist excerpt (pin names and nets, part order shuffled) for the footprints in the layout excerpt that follows; sources: Cadence DE-HDL packaged netlist, KiCad conversion of Wiwynn_Tioga_Pass_MB.brd

C22W14  SC22U16V5MX-4-GP  20%  pkg SMD-BCG5  page 214 : \1\ = VR_FET_SW_P12V_STBY_PVCCIN_CPU0 ; \2\ = GND
C9L2  CAPP  470UF 2.5V 20% ALUM  pkg 3018  page 228 : A = PVDDQ_KLM ; B = GND
R4U4  RES  33.0K 5% CHIP  pkg 0402  page 94 : A = FM_DIMM_EVENT_FET ; B = GND

(kicad_pcb
	(version 20260206)
	(generator "pcbnew")
	(generator_version "10.0")
	(general
		(thickness 1.6)
		(legacy_teardrops no)
	)
	(paper "A4")
	(title_block
		(title "Wiwynn_Tioga_Pass_MB.brd")
		(comment 1 "Tioga Pass / footprints 3237-3239 of 4770")
	)
	(layers
		(0 "F.Cu" signal "TOP")
		(4 "In1.Cu" signal "L2GND")
		(6 "In2.Cu" signal "L3")
		(8 "In3.Cu" signal "L4GND")
		(10 "In4.Cu" signal "L5")
		(12 "In5.Cu" signal "L6GND")
		(14 "In6.Cu" signal "L7VCC")
		(16 "In7.Cu" signal "L8VCC")
		(18 "In8.Cu" signal "L9GND")
		(20 "In9.Cu" signal "L10")
		(22 "In10.Cu" signal "L11GND")
		(24 "In11.Cu" signal "L12")
		(26 "In12.Cu" signal "L13GND")
		(2 "B.Cu" signal "BOTTOM")
		(9 "F.Adhes" user "F.Adhesive")
		(11 "B.Adhes" user "B.Adhesive")
		(13 "F.Paste" user "Package Geometry/Pastemask Top")
		(15 "B.Paste" user "Package Geometry/Pastemask Bottom")
		(5 "F.SilkS" user "Ref Des/Silkscreen Top")
		(7 "B.SilkS" user "Ref Des/Silkscreen Bottom")
		(1 "F.Mask" user "Board Geometry/Soldermask Top")
		(3 "B.Mask" user "Board Geometry/Soldermask Bottom")
		(17 "Dwgs.User" user "User.Drawings")
		(19 "Cmts.User" user "User.Comments")
		(21 "Eco1.User" user "User.Eco1")
		(23 "Eco2.User" user "User.Eco2")
		(25 "Edge.Cuts" user "Board Geometry/Outline")
		(27 "Margin" user)
		(31 "F.CrtYd" user "Package Geometry/Place Bound Top")
		(29 "B.CrtYd" user "Package Geometry/Place Bound Bottom")
		(35 "F.Fab" user "Ref Des/Assembly Top")
		(33 "B.Fab" user "Ref Des/Assembly Bottom")
	)
	(footprint ""
		(layer "B.Cu")
		(at 330.581 -5.969)
		(property "Reference" "R4U4"
			(at 0 0 0)
			(layer "B.SilkS")
			(hide yes)
			(effects
				(font
					(size 1.27 1.27)
				)
				(justify mirror)
			)
		)
		(property "Value" ""
			(at 0 0 0)
			(layer "B.Fab")
			(effects
				(font
					(size 1.27 1.27)
				)
				(justify mirror)
			)
		)
		(duplicate_pad_numbers_are_jumpers no)
		(fp_poly
			(pts
				(xy 0.2794 -0.1016) (xy -0.2794 -0.1016) (xy -0.2794 0.9906) (xy 0.2794 0.9906)
			)
			(stroke
				(width 0)
				(type default)
			)
			(fill no)
			(layer "B.CrtYd")
		)
		(fp_line
			(start -0.2794 -0.1016)
			(end 0.2794 -0.1016)
			(stroke
				(width 0.1)
				(type default)
			)
			(layer "B.Fab")
		)
		(fp_line
			(start -0.2794 0.9906)
			(end -0.2794 -0.1016)
			(stroke
				(width 0.1)
				(type default)
			)
			(layer "B.Fab")
		)
		(fp_line
			(start 0.2794 -0.1016)
			(end 0.2794 0.9906)
			(stroke
				(width 0.1)
				(type default)
			)
			(layer "B.Fab")
		)
		(fp_line
			(start 0.2794 0.9906)
			(end -0.2794 0.9906)
			(stroke
				(width 0.1)
				(type default)
			)
			(layer "B.Fab")
		)
		(pad "1" smd rect
			(at 0 0 180)
			(size 0.508 0.508)
			(layers "B.Cu" "B.Mask" "B.Paste")
			(net "FM_DIMM_EVENT_FET")
		)
		(pad "2" smd rect
			(at 0 0.889 180)
			(size 0.508 0.508)
			(layers "B.Cu" "B.Mask" "B.Paste")
			(net "GND")
		)
		(zone
			(layer "B.Cu")
			(hatch none 0.5)
			(connect_pads
				(clearance 0)
			)
			(min_thickness 0.25)
			(keepout
				(tracks allowed)
				(vias not_allowed)
				(pads allowed)
				(copperpour not_allowed)
				(footprints allowed)
			)
			(placement
				(enabled no)
				(sheetname "")
			)
			(fill
				(thermal_gap 0.5)
				(thermal_bridge_width 0.5)
				(island_removal_mode 0)
			)
			(polygon
				(pts
					(xy 330.835 -5.715) (xy 330.327 -5.715) (xy 330.327 -5.334) (xy 330.835 -5.334)
				)
			)
		)
		(zone
			(layer "B.Cu")
			(hatch none 0.5)
			(connect_pads
				(clearance 0)
			)
			(min_thickness 0.25)
			(keepout
				(tracks not_allowed)
				(vias allowed)
				(pads allowed)
				(copperpour not_allowed)
				(footprints allowed)
			)
			(placement
				(enabled no)
				(sheetname "")
			)
			(fill
				(thermal_gap 0.5)
				(thermal_bridge_width 0.5)
				(island_removal_mode 0)
			)
			(polygon
				(pts
					(xy 330.835 -5.334) (xy 330.327 -5.334) (xy 330.327 -5.715) (xy 330.835 -5.715)
				)
			)
		)
	)
	(footprint ""
		(layer "B.Cu")
		(at 183.795416 -59.238896 180)
		(property "Reference" "C22W14"
			(at 0 0 0)
			(layer "B.SilkS")
			(hide yes)
			(effects
				(font
					(size 1.27 1.27)
				)
				(justify mirror)
			)
		)
		(property "Value" "*"
			(at 0.0762 -6.2357 180)
			(unlocked yes)
			(layer "B.Fab")
			(hide yes)
			(effects
				(font
					(size 1.27 1.016)
					(thickness 0.1524)
				)
				(justify mirror)
			)
		)
		(property "Device Type" "SC22U16V5MX-4-GP_SMD-BCG5-SC22A"
			(at 0.0762 -8.2677 180)
			(unlocked yes)
			(layer "B.Fab")
			(hide yes)
			(effects
				(font
					(size 1.27 1.016)
					(thickness 0.1524)
				)
				(justify mirror)
			)
		)
		(duplicate_pad_numbers_are_jumpers no)
		(fp_line
			(start -0.635 0)
			(end 0.635 0)
			(stroke
				(width 0.508)
				(type default)
			)
			(layer "B.SilkS")
		)
		(fp_rect
			(start 0.9652 1.778)
			(end -0.9652 -1.778)
			(stroke
				(width 0)
				(type default)
			)
			(fill no)
			(layer "B.CrtYd")
		)
		(fp_poly
			(pts
				(xy 0.9652 -1.778) (xy -0.9652 -1.778) (xy -0.9652 1.778) (xy 0.9652 1.778)
			)
			(stroke
				(width 0)
				(type default)
			)
			(fill no)
			(layer "B.Fab")
		)
		(pad "1" smd rect
			(at 0 -0.9652)
			(size 1.397 1.143)
			(layers "B.Cu" "B.Mask" "B.Paste")
			(net "VR_FET_SW_P12V_STBY_PVCCIN_CPU0")
		)
		(pad "2" smd rect
			(at 0 0.9652)
			(size 1.397 1.143)
			(layers "B.Cu" "B.Mask" "B.Paste")
			(net "GND")
		)
	)
	(footprint ""
		(layer "B.Cu")
		(at 18.0594 -154.5844 -90)
		(property "Reference" "C9L2"
			(at -2.99593 5.1054 0)
			(unlocked yes)
			(layer "B.SilkS")
			(effects
				(font
					(size 0.7874 0.5842)
					(thickness 0.1524)
				)
				(justify mirror)
			)
		)
		(property "Value" ""
			(at 0 0 90)
			(layer "B.Fab")
			(effects
				(font
					(size 1.27 1.27)
				)
				(justify mirror)
			)
		)
		(duplicate_pad_numbers_are_jumpers no)
		(fp_line
			(start -2.286 7.366)
			(end -1.600708 7.366)
			(stroke
				(width 0.1524)
				(type default)
			)
			(layer "B.SilkS")
		)
		(fp_line
			(start -2.286 7.366)
			(end -2.286 1.63195)
			(stroke
				(width 0.1524)
				(type default)
			)
			(layer "B.SilkS")
		)
		(fp_line
			(start 2.286 7.366)
			(end 1.60147 7.366)
			(stroke
				(width 0.1524)
				(type default)
			)
			(layer "B.SilkS")
		)
		(fp_line
			(start 2.286 7.366)
			(end 2.286 1.632712)
			(stroke
				(width 0.1524)
				(type default)
			)
			(layer "B.SilkS")
		)
		(fp_line
			(start -2.504948 1.633728)
			(end -1.6002 1.633728)
			(stroke
				(width 0.1524)
				(type default)
			)
			(layer "B.SilkS")
		)
		(fp_line
			(start 2.563114 1.633728)
			(end 1.6002 1.633728)
			(stroke
				(width 0.1524)
				(type default)
			)
			(layer "B.SilkS")
		)
		(fp_line
			(start -2.504948 -1.616456)
			(end -2.504948 1.633728)
			(stroke
				(width 0.1524)
				(type default)
			)
			(layer "B.SilkS")
		)
		(fp_line
			(start -1.6002 -1.616456)
			(end -2.504948 -1.616456)
			(stroke
				(width 0.1524)
				(type default)
			)
			(layer "B.SilkS")
		)
		(fp_line
			(start 1.6002 -1.616456)
			(end 2.563114 -1.616456)
			(stroke
				(width 0.1524)
				(type default)
			)
			(layer "B.SilkS")
		)
		(fp_line
			(start 2.563114 -1.616456)
			(end 2.563114 1.633728)
			(stroke
				(width 0.1524)
				(type default)
			)
			(layer "B.SilkS")
		)
		(fp_rect
			(start 2.286 -0.254)
			(end -2.286 7.366)
			(stroke
				(width 0)
				(type default)
			)
			(fill no)
			(layer "B.CrtYd")
		)
		(fp_line
			(start -2.286 7.366)
			(end 2.286 7.366)
			(stroke
				(width 0.1)
				(type default)
			)
			(layer "B.Fab")
		)
		(fp_line
			(start 2.286 7.366)
			(end 2.286 -0.254)
			(stroke
				(width 0.1)
				(type default)
			)
			(layer "B.Fab")
		)
		(fp_line
			(start -2.286 -0.254)
			(end -2.286 7.366)
			(stroke
				(width 0.1)
				(type default)
			)
			(layer "B.Fab")
		)
		(fp_line
			(start 2.286 -0.254)
			(end -2.286 -0.254)
			(stroke
				(width 0.1)
				(type default)
			)
			(layer "B.Fab")
		)
		(pad "1" smd rect
			(at 0 0 90)
			(size 2.54 3.048)
			(layers "B.Cu" "B.Mask" "B.Paste")
			(net "PVDDQ_KLM")
		)
		(pad "2" smd rect
			(at 0 7.112 90)
			(size 2.54 3.048)
			(layers "B.Cu" "B.Mask" "B.Paste")
			(net "GND")
		)
	)
)
